# S9S_MB_2U (Grand Teton) — schematic netlist excerpt (pin names and nets, part order shuffled) for the footprints in the layout excerpt that follows; sources: Cadence DE-HDL packaged netlist, KiCad conversion of 03242023_DA0F0TMBIJ0_F0T_Motherboard_J_brd_V01_OCP.brd

C496  Q_CAP  47UF 4V 20% X6S  pkg C0805  page 75 : A = PVCCFA_EHV_CPU0 ; B = GND
R3210  Q_RES  22 1% EMPTY  pkg 0402LF  page 160 : A = NCSI_BMC_CRS_DV_R1 ; B = RMII_OCP_BMC_CRSDV
PR323  Q_RES  1 1% CHIP  pkg 0402LF  page 284 : A = PVCCIN_CPU1_VCC ; B = P3V3_AUX

(kicad_pcb
	(version 20260206)
	(generator "pcbnew")
	(generator_version "10.0")
	(general
		(thickness 1.6)
		(legacy_teardrops no)
	)
	(paper "A4")
	(title_block
		(title "03242023_DA0F0TMBIJ0_F0T_Motherboard_J_brd_V01_OCP.brd")
		(comment 1 "Grand Teton / footprints 4777-4779 of 6105")
	)
	(layers
		(0 "F.Cu" signal "TOP")
		(4 "In1.Cu" signal "GND")
		(6 "In2.Cu" signal "IN1")
		(8 "In3.Cu" signal "GND1")
		(10 "In4.Cu" signal "IN2")
		(12 "In5.Cu" signal "GND2")
		(14 "In6.Cu" signal "IN3")
		(16 "In7.Cu" signal "GND3")
		(18 "In8.Cu" signal "VCC")
		(20 "In9.Cu" signal "VCC1")
		(22 "In10.Cu" signal "GND4")
		(24 "In11.Cu" signal "IN4")
		(26 "In12.Cu" signal "GND5")
		(28 "In13.Cu" signal "IN5")
		(30 "In14.Cu" signal "GND6")
		(32 "In15.Cu" signal "IN6")
		(34 "In16.Cu" signal "GND7")
		(2 "B.Cu" signal "BOTTOM")
		(9 "F.Adhes" user "F.Adhesive")
		(11 "B.Adhes" user "B.Adhesive")
		(13 "F.Paste" user "Package Geometry/Pastemask Top")
		(15 "B.Paste" user "Package Geometry/Pastemask Bottom")
		(5 "F.SilkS" user "Ref Des/Silkscreen Top")
		(7 "B.SilkS" user "Ref Des/Silkscreen Bottom")
		(1 "F.Mask" user "Board Geometry/Soldermask Top")
		(3 "B.Mask" user "Board Geometry/Soldermask Bottom")
		(17 "Dwgs.User" user "User.Drawings")
		(19 "Cmts.User" user "User.Comments")
		(21 "Eco1.User" user "User.Eco1")
		(23 "Eco2.User" user "User.Eco2")
		(25 "Edge.Cuts" user "Board Geometry/Outline")
		(27 "Margin" user)
		(31 "F.CrtYd" user "Package Geometry/Place Bound Top")
		(29 "B.CrtYd" user "Package Geometry/Place Bound Bottom")
		(35 "F.Fab" user "Ref Des/Assembly Top")
		(33 "B.Fab" user "Ref Des/Assembly Bottom")
	)
	(footprint ""
		(layer "B.Cu")
		(at 203.072746 -75.053952)
		(property "Reference" "R3210"
			(at 0 0 0)
			(layer "B.SilkS")
			(hide yes)
			(effects
				(font
					(size 1.27 1.27)
				)
				(justify mirror)
			)
		)
		(property "Value" ""
			(at 0 0 0)
			(layer "B.Fab")
			(effects
				(font
					(size 1.27 1.27)
				)
				(justify mirror)
			)
		)
		(duplicate_pad_numbers_are_jumpers no)
		(fp_line
			(start -0.7874 -0.4064)
			(end -0.7874 0.4064)
			(stroke
				(width 0.1524)
				(type default)
			)
			(layer "B.SilkS")
		)
		(fp_line
			(start -0.7874 0.4064)
			(end 0.7874 0.4064)
			(stroke
				(width 0.1524)
				(type default)
			)
			(layer "B.SilkS")
		)
		(fp_line
			(start 0.7874 -0.4064)
			(end -0.7874 -0.4064)
			(stroke
				(width 0.1524)
				(type default)
			)
			(layer "B.SilkS")
		)
		(fp_line
			(start 0.7874 0.4064)
			(end 0.7874 -0.4064)
			(stroke
				(width 0.1524)
				(type default)
			)
			(layer "B.SilkS")
		)
		(fp_line
			(start -0.67945 -0.3048)
			(end -0.67945 0.3048)
			(stroke
				(width 0.1)
				(type default)
			)
			(layer "B.Fab")
		)
		(fp_line
			(start -0.67945 0.3048)
			(end -0.120396 0.3048)
			(stroke
				(width 0.1)
				(type default)
			)
			(layer "B.Fab")
		)
		(fp_line
			(start -0.12065 -0.3048)
			(end -0.67945 -0.3048)
			(stroke
				(width 0.1)
				(type default)
			)
			(layer "B.Fab")
		)
		(fp_line
			(start -0.12065 -0.2794)
			(end -0.12065 -0.3048)
			(stroke
				(width 0.1)
				(type default)
			)
			(layer "B.Fab")
		)
		(fp_line
			(start -0.120396 0.2794)
			(end 0.12065 0.2794)
			(stroke
				(width 0.1)
				(type default)
			)
			(layer "B.Fab")
		)
		(fp_line
			(start -0.120396 0.3048)
			(end -0.120396 0.2794)
			(stroke
				(width 0.1)
				(type default)
			)
			(layer "B.Fab")
		)
		(fp_line
			(start 0.12065 -0.305054)
			(end 0.12065 -0.2794)
			(stroke
				(width 0.1)
				(type default)
			)
			(layer "B.Fab")
		)
		(fp_line
			(start 0.12065 -0.2794)
			(end -0.12065 -0.2794)
			(stroke
				(width 0.1)
				(type default)
			)
			(layer "B.Fab")
		)
		(fp_line
			(start 0.12065 0.2794)
			(end 0.12065 0.3048)
			(stroke
				(width 0.1)
				(type default)
			)
			(layer "B.Fab")
		)
		(fp_line
			(start 0.12065 0.3048)
			(end 0.67945 0.3048)
			(stroke
				(width 0.1)
				(type default)
			)
			(layer "B.Fab")
		)
		(fp_line
			(start 0.67945 -0.305054)
			(end 0.12065 -0.305054)
			(stroke
				(width 0.1)
				(type default)
			)
			(layer "B.Fab")
		)
		(fp_line
			(start 0.67945 0.3048)
			(end 0.67945 -0.305054)
			(stroke
				(width 0.1)
				(type default)
			)
			(layer "B.Fab")
		)
		(pad "1" smd circle
			(at 0.40005 0 180)
			(size 0 0)
			(layers "B.Cu" "B.Mask" "B.Paste")
			(net "NCSI_BMC_CRS_DV_R1")
		)
		(pad "2" smd circle
			(at -0.40005 0 180)
			(size 0 0)
			(layers "B.Cu" "B.Mask" "B.Paste")
			(net "RMII_OCP_BMC_CRSDV")
		)
	)
	(footprint ""
		(layer "B.Cu")
		(at 113.78438 -362.703872 180)
		(property "Reference" "PR323"
			(at 0 0 0)
			(layer "B.SilkS")
			(hide yes)
			(effects
				(font
					(size 1.27 1.27)
				)
				(justify mirror)
			)
		)
		(property "Value" ""
			(at 0 0 0)
			(layer "B.Fab")
			(effects
				(font
					(size 1.27 1.27)
				)
				(justify mirror)
			)
		)
		(duplicate_pad_numbers_are_jumpers no)
		(fp_line
			(start 0.7874 0.4064)
			(end 0.7874 -0.4064)
			(stroke
				(width 0.1524)
				(type default)
			)
			(layer "B.SilkS")
		)
		(fp_line
			(start 0.7874 -0.4064)
			(end -0.7874 -0.4064)
			(stroke
				(width 0.1524)
				(type default)
			)
			(layer "B.SilkS")
		)
		(fp_line
			(start -0.7874 0.4064)
			(end 0.7874 0.4064)
			(stroke
				(width 0.1524)
				(type default)
			)
			(layer "B.SilkS")
		)
		(fp_line
			(start -0.7874 -0.4064)
			(end -0.7874 0.4064)
			(stroke
				(width 0.1524)
				(type default)
			)
			(layer "B.SilkS")
		)
		(fp_line
			(start 0.67945 0.3048)
			(end 0.67945 -0.305054)
			(stroke
				(width 0.1)
				(type default)
			)
			(layer "B.Fab")
		)
		(fp_line
			(start 0.67945 -0.305054)
			(end 0.12065 -0.305054)
			(stroke
				(width 0.1)
				(type default)
			)
			(layer "B.Fab")
		)
		(fp_line
			(start 0.12065 0.3048)
			(end 0.67945 0.3048)
			(stroke
				(width 0.1)
				(type default)
			)
			(layer "B.Fab")
		)
		(fp_line
			(start 0.12065 0.2794)
			(end 0.12065 0.3048)
			(stroke
				(width 0.1)
				(type default)
			)
			(layer "B.Fab")
		)
		(fp_line
			(start 0.12065 -0.2794)
			(end -0.12065 -0.2794)
			(stroke
				(width 0.1)
				(type default)
			)
			(layer "B.Fab")
		)
		(fp_line
			(start 0.12065 -0.305054)
			(end 0.12065 -0.2794)
			(stroke
				(width 0.1)
				(type default)
			)
			(layer "B.Fab")
		)
		(fp_line
			(start -0.120396 0.3048)
			(end -0.120396 0.2794)
			(stroke
				(width 0.1)
				(type default)
			)
			(layer "B.Fab")
		)
		(fp_line
			(start -0.120396 0.2794)
			(end 0.12065 0.2794)
			(stroke
				(width 0.1)
				(type default)
			)
			(layer "B.Fab")
		)
		(fp_line
			(start -0.12065 -0.2794)
			(end -0.12065 -0.3048)
			(stroke
				(width 0.1)
				(type default)
			)
			(layer "B.Fab")
		)
		(fp_line
			(start -0.12065 -0.3048)
			(end -0.67945 -0.3048)
			(stroke
				(width 0.1)
				(type default)
			)
			(layer "B.Fab")
		)
		(fp_line
			(start -0.67945 0.3048)
			(end -0.120396 0.3048)
			(stroke
				(width 0.1)
				(type default)
			)
			(layer "B.Fab")
		)
		(fp_line
			(start -0.67945 -0.3048)
			(end -0.67945 0.3048)
			(stroke
				(width 0.1)
				(type default)
			)
			(layer "B.Fab")
		)
		(pad "1" smd circle
			(at 0.40005 0)
			(size 0 0)
			(layers "B.Cu" "B.Mask" "B.Paste")
			(net "PVCCIN_CPU1_VCC")
		)
		(pad "2" smd circle
			(at -0.40005 0)
			(size 0 0)
			(layers "B.Cu" "B.Mask" "B.Paste")
			(net "P3V3_AUX")
		)
	)
	(footprint ""
		(layer "B.Cu")
		(at 351.841308 -259.532882 -90)
		(property "Reference" "C496"
			(at 0 0 90)
			(layer "B.SilkS")
			(hide yes)
			(effects
				(font
					(size 1.27 1.27)
				)
				(justify mirror)
			)
		)
		(property "Value" ""
			(at 0 0 90)
			(layer "B.Fab")
			(effects
				(font
					(size 1.27 1.27)
				)
				(justify mirror)
			)
		)
		(duplicate_pad_numbers_are_jumpers no)
		(fp_line
			(start -1.524 0.762)
			(end 1.524 0.762)
			(stroke
				(width 0.1524)
				(type default)
			)
			(layer "B.SilkS")
		)
		(fp_line
			(start 1.524 0.762)
			(end 1.524 -0.762)
			(stroke
				(width 0.1524)
				(type default)
			)
			(layer "B.SilkS")
		)
		(fp_line
			(start -1.524 -0.762)
			(end -1.524 0.762)
			(stroke
				(width 0.1524)
				(type default)
			)
			(layer "B.SilkS")
		)
		(fp_line
			(start 1.524 -0.762)
			(end -1.524 -0.762)
			(stroke
				(width 0.1524)
				(type default)
			)
			(layer "B.SilkS")
		)
		(fp_line
			(start -1.1049 0.724916)
			(end -1.1049 -0.724916)
			(stroke
				(width 0.1)
				(type default)
			)
			(layer "B.Fab")
		)
		(fp_line
			(start 1.1049 0.724916)
			(end -1.1049 0.724916)
			(stroke
				(width 0.1)
				(type default)
			)
			(layer "B.Fab")
		)
		(fp_line
			(start -1.1049 -0.724916)
			(end 1.1049 -0.724916)
			(stroke
				(width 0.1)
				(type default)
			)
			(layer "B.Fab")
		)
		(fp_line
			(start 1.1049 -0.724916)
			(end 1.1049 0.724916)
			(stroke
				(width 0.1)
				(type default)
			)
			(layer "B.Fab")
		)
		(pad "1" smd rect
			(at 0.889 0 270)
			(size 1.016 1.27)
			(layers "B.Cu" "B.Mask" "B.Paste")
			(net "PVCCFA_EHV_CPU0")
		)
		(pad "2" smd rect
			(at -0.889 0 270)
			(size 1.016 1.27)
			(layers "B.Cu" "B.Mask" "B.Paste")
			(net "GND")
		)
	)
)
